(kicad_pcb
	(version 20260206)
	(generator "pcbnew")
	(generator_version "10.0")
	(general
		(thickness 1.6)
		(legacy_teardrops no)
	)
	(paper "A4")
	(title_block
		(title "01162023_DA0F0TEBIF0_F0T_Expander_BD_F_brd_V02_OCP.brd")
		(comment 1 "Grand Teton / footprints 611-616 of 9728")
	)
	(layers
		(0 "F.Cu" signal "TOP")
		(4 "In1.Cu" signal "GND")
		(6 "In2.Cu" signal "VCC")
		(8 "In3.Cu" signal "VCC1")
		(10 "In4.Cu" signal "GND1")
		(12 "In5.Cu" signal "IN1")
		(14 "In6.Cu" signal "GND2")
		(16 "In7.Cu" signal "IN2")
		(18 "In8.Cu" signal "GND3")
		(20 "In9.Cu" signal "IN3")
		(22 "In10.Cu" signal "GND4")
		(24 "In11.Cu" signal "IN4")
		(26 "In12.Cu" signal "GND5")
		(28 "In13.Cu" signal "IN5")
		(30 "In14.Cu" signal "GND6")
		(32 "In15.Cu" signal "IN6")
		(34 "In16.Cu" signal "GND7")
		(2 "B.Cu" signal "BOTTOM")
		(9 "F.Adhes" user "F.Adhesive")
		(11 "B.Adhes" user "B.Adhesive")
		(13 "F.Paste" user "Package Geometry/Pastemask Top")
		(15 "B.Paste" user "Package Geometry/Pastemask Bottom")
		(5 "F.SilkS" user "Ref Des/Silkscreen Top")
		(7 "B.SilkS" user "Ref Des/Silkscreen Bottom")
		(1 "F.Mask" user "Board Geometry/Soldermask Top")
		(3 "B.Mask" user "Board Geometry/Soldermask Bottom")
		(17 "Dwgs.User" user "User.Drawings")
		(19 "Cmts.User" user "User.Comments")
		(21 "Eco1.User" user "User.Eco1")
		(23 "Eco2.User" user "User.Eco2")
		(25 "Edge.Cuts" user "Board Geometry/Outline")
		(27 "Margin" user)
		(31 "F.CrtYd" user "Package Geometry/Place Bound Top")
		(29 "B.CrtYd" user "Package Geometry/Place Bound Bottom")
		(35 "F.Fab" user "Ref Des/Assembly Top")
		(33 "B.Fab" user "Ref Des/Assembly Bottom")
	)
	(footprint ""
		(layer "F.Cu")
		(at 121.13514 -99.463606)
		(property "Reference" "R1557"
			(at 0 0 0)
			(layer "F.SilkS")
			(hide yes)
			(effects
				(font
					(size 1.27 1.27)
				)
			)
		)
		(property "Value" ""
			(at 0 0 0)
			(layer "F.Fab")
			(effects
				(font
					(size 1.27 1.27)
				)
			)
		)
		(duplicate_pad_numbers_are_jumpers no)
		(fp_line
			(start -0.7874 -0.4064)
			(end 0.7874 -0.4064)
			(stroke
				(width 0.1524)
				(type default)
			)
			(layer "F.SilkS")
		)
		(fp_line
			(start -0.7874 0.4064)
			(end -0.7874 -0.4064)
			(stroke
				(width 0.1524)
				(type default)
			)
			(layer "F.SilkS")
		)
		(fp_line
			(start 0.7874 -0.4064)
			(end 0.7874 0.4064)
			(stroke
				(width 0.1524)
				(type default)
			)
			(layer "F.SilkS")
		)
		(fp_line
			(start 0.7874 0.4064)
			(end -0.7874 0.4064)
			(stroke
				(width 0.1524)
				(type default)
			)
			(layer "F.SilkS")
		)
		(fp_line
			(start -0.67945 -0.305054)
			(end -0.12065 -0.305054)
			(stroke
				(width 0.1)
				(type default)
			)
			(layer "F.Fab")
		)
		(fp_line
			(start -0.67945 0.3048)
			(end -0.67945 -0.305054)
			(stroke
				(width 0.1)
				(type default)
			)
			(layer "F.Fab")
		)
		(fp_line
			(start -0.12065 -0.305054)
			(end -0.12065 -0.2794)
			(stroke
				(width 0.1)
				(type default)
			)
			(layer "F.Fab")
		)
		(fp_line
			(start -0.12065 -0.2794)
			(end 0.12065 -0.2794)
			(stroke
				(width 0.1)
				(type default)
			)
			(layer "F.Fab")
		)
		(fp_line
			(start -0.12065 0.2794)
			(end -0.12065 0.3048)
			(stroke
				(width 0.1)
				(type default)
			)
			(layer "F.Fab")
		)
		(fp_line
			(start -0.12065 0.3048)
			(end -0.67945 0.3048)
			(stroke
				(width 0.1)
				(type default)
			)
			(layer "F.Fab")
		)
		(fp_line
			(start 0.120396 0.2794)
			(end -0.12065 0.2794)
			(stroke
				(width 0.1)
				(type default)
			)
			(layer "F.Fab")
		)
		(fp_line
			(start 0.120396 0.3048)
			(end 0.120396 0.2794)
			(stroke
				(width 0.1)
				(type default)
			)
			(layer "F.Fab")
		)
		(fp_line
			(start 0.12065 -0.3048)
			(end 0.67945 -0.3048)
			(stroke
				(width 0.1)
				(type default)
			)
			(layer "F.Fab")
		)
		(fp_line
			(start 0.12065 -0.2794)
			(end 0.12065 -0.3048)
			(stroke
				(width 0.1)
				(type default)
			)
			(layer "F.Fab")
		)
		(fp_line
			(start 0.67945 -0.3048)
			(end 0.67945 0.3048)
			(stroke
				(width 0.1)
				(type default)
			)
			(layer "F.Fab")
		)
		(fp_line
			(start 0.67945 0.3048)
			(end 0.120396 0.3048)
			(stroke
				(width 0.1)
				(type default)
			)
			(layer "F.Fab")
		)
		(pad "1" smd circle
			(at -0.40005 0)
			(size 0 0)
			(layers "F.Cu" "F.Mask" "F.Paste")
			(net "P3V3_AUX")
		)
		(pad "2" smd circle
			(at 0.40005 0)
			(size 0 0)
			(layers "F.Cu" "F.Mask" "F.Paste")
			(net "BIC_I2C9_SSD_MUX0_A0")
		)
	)
	(footprint ""
		(layer "F.Cu")
		(at 366.638586 -263.121394 -90)
		(property "Reference" "R3067"
			(at 0 0 270)
			(layer "F.SilkS")
			(hide yes)
			(effects
				(font
					(size 1.27 1.27)
				)
			)
		)
		(property "Value" ""
			(at 0 0 270)
			(layer "F.Fab")
			(effects
				(font
					(size 1.27 1.27)
				)
			)
		)
		(duplicate_pad_numbers_are_jumpers no)
		(fp_line
			(start -0.7874 0.4064)
			(end -0.7874 -0.4064)
			(stroke
				(width 0.1524)
				(type default)
			)
			(layer "F.SilkS")
		)
		(fp_line
			(start 0.7874 0.4064)
			(end -0.7874 0.4064)
			(stroke
				(width 0.1524)
				(type default)
			)
			(layer "F.SilkS")
		)
		(fp_line
			(start -0.7874 -0.4064)
			(end 0.7874 -0.4064)
			(stroke
				(width 0.1524)
				(type default)
			)
			(layer "F.SilkS")
		)
		(fp_line
			(start 0.7874 -0.4064)
			(end 0.7874 0.4064)
			(stroke
				(width 0.1524)
				(type default)
			)
			(layer "F.SilkS")
		)
		(fp_line
			(start -0.67945 0.3048)
			(end -0.67945 -0.305054)
			(stroke
				(width 0.1)
				(type default)
			)
			(layer "F.Fab")
		)
		(fp_line
			(start -0.12065 0.3048)
			(end -0.67945 0.3048)
			(stroke
				(width 0.1)
				(type default)
			)
			(layer "F.Fab")
		)
		(fp_line
			(start 0.120396 0.3048)
			(end 0.120396 0.2794)
			(stroke
				(width 0.1)
				(type default)
			)
			(layer "F.Fab")
		)
		(fp_line
			(start 0.67945 0.3048)
			(end 0.120396 0.3048)
			(stroke
				(width 0.1)
				(type default)
			)
			(layer "F.Fab")
		)
		(fp_line
			(start -0.12065 0.2794)
			(end -0.12065 0.3048)
			(stroke
				(width 0.1)
				(type default)
			)
			(layer "F.Fab")
		)
		(fp_line
			(start 0.120396 0.2794)
			(end -0.12065 0.2794)
			(stroke
				(width 0.1)
				(type default)
			)
			(layer "F.Fab")
		)
		(fp_line
			(start -0.12065 -0.2794)
			(end 0.12065 -0.2794)
			(stroke
				(width 0.1)
				(type default)
			)
			(layer "F.Fab")
		)
		(fp_line
			(start 0.12065 -0.2794)
			(end 0.12065 -0.3048)
			(stroke
				(width 0.1)
				(type default)
			)
			(layer "F.Fab")
		)
		(fp_line
			(start 0.12065 -0.3048)
			(end 0.67945 -0.3048)
			(stroke
				(width 0.1)
				(type default)
			)
			(layer "F.Fab")
		)
		(fp_line
			(start 0.67945 -0.3048)
			(end 0.67945 0.3048)
			(stroke
				(width 0.1)
				(type default)
			)
			(layer "F.Fab")
		)
		(fp_line
			(start -0.67945 -0.305054)
			(end -0.12065 -0.305054)
			(stroke
				(width 0.1)
				(type default)
			)
			(layer "F.Fab")
		)
		(fp_line
			(start -0.12065 -0.305054)
			(end -0.12065 -0.2794)
			(stroke
				(width 0.1)
				(type default)
			)
			(layer "F.Fab")
		)
		(pad "1" smd circle
			(at -0.40005 0 270)
			(size 0 0)
			(layers "F.Cu" "F.Mask" "F.Paste")
			(net "PWR_EN_PEX_R")
		)
		(pad "2" smd circle
			(at 0.40005 0 270)
			(size 0 0)
			(layers "F.Cu" "F.Mask" "F.Paste")
			(net "PWR_EN_PEX_BUF")
		)
	)
	(footprint ""
		(layer "F.Cu")
		(at 238.418878 -93.017594 90)
		(property "Reference" "R6843"
			(at 0 0 90)
			(layer "F.SilkS")
			(hide yes)
			(effects
				(font
					(size 1.27 1.27)
				)
			)
		)
		(property "Value" ""
			(at 0 0 90)
			(layer "F.Fab")
			(effects
				(font
					(size 1.27 1.27)
				)
			)
		)
		(duplicate_pad_numbers_are_jumpers no)
		(fp_line
			(start 0.7874 -0.4064)
			(end 0.7874 0.4064)
			(stroke
				(width 0.1524)
				(type default)
			)
			(layer "F.SilkS")
		)
		(fp_line
			(start -0.7874 -0.4064)
			(end 0.7874 -0.4064)
			(stroke
				(width 0.1524)
				(type default)
			)
			(layer "F.SilkS")
		)
		(fp_line
			(start 0.7874 0.4064)
			(end -0.7874 0.4064)
			(stroke
				(width 0.1524)
				(type default)
			)
			(layer "F.SilkS")
		)
		(fp_line
			(start -0.7874 0.4064)
			(end -0.7874 -0.4064)
			(stroke
				(width 0.1524)
				(type default)
			)
			(layer "F.SilkS")
		)
		(fp_line
			(start -0.12065 -0.305054)
			(end -0.12065 -0.2794)
			(stroke
				(width 0.1)
				(type default)
			)
			(layer "F.Fab")
		)
		(fp_line
			(start -0.67945 -0.305054)
			(end -0.12065 -0.305054)
			(stroke
				(width 0.1)
				(type default)
			)
			(layer "F.Fab")
		)
		(fp_line
			(start 0.67945 -0.3048)
			(end 0.67945 0.3048)
			(stroke
				(width 0.1)
				(type default)
			)
			(layer "F.Fab")
		)
		(fp_line
			(start 0.12065 -0.3048)
			(end 0.67945 -0.3048)
			(stroke
				(width 0.1)
				(type default)
			)
			(layer "F.Fab")
		)
		(fp_line
			(start 0.12065 -0.2794)
			(end 0.12065 -0.3048)
			(stroke
				(width 0.1)
				(type default)
			)
			(layer "F.Fab")
		)
		(fp_line
			(start -0.12065 -0.2794)
			(end 0.12065 -0.2794)
			(stroke
				(width 0.1)
				(type default)
			)
			(layer "F.Fab")
		)
		(fp_line
			(start 0.120396 0.2794)
			(end -0.12065 0.2794)
			(stroke
				(width 0.1)
				(type default)
			)
			(layer "F.Fab")
		)
		(fp_line
			(start -0.12065 0.2794)
			(end -0.12065 0.3048)
			(stroke
				(width 0.1)
				(type default)
			)
			(layer "F.Fab")
		)
		(fp_line
			(start 0.67945 0.3048)
			(end 0.120396 0.3048)
			(stroke
				(width 0.1)
				(type default)
			)
			(layer "F.Fab")
		)
		(fp_line
			(start 0.120396 0.3048)
			(end 0.120396 0.2794)
			(stroke
				(width 0.1)
				(type default)
			)
			(layer "F.Fab")
		)
		(fp_line
			(start -0.12065 0.3048)
			(end -0.67945 0.3048)
			(stroke
				(width 0.1)
				(type default)
			)
			(layer "F.Fab")
		)
		(fp_line
			(start -0.67945 0.3048)
			(end -0.67945 -0.305054)
			(stroke
				(width 0.1)
				(type default)
			)
			(layer "F.Fab")
		)
		(pad "1" smd circle
			(at -0.40005 0 90)
			(size 0 0)
			(layers "F.Cu" "F.Mask" "F.Paste")
			(net "PEX_USB_HUB_XOUT")
		)
		(pad "2" smd circle
			(at 0.40005 0 90)
			(size 0 0)
			(layers "F.Cu" "F.Mask" "F.Paste")
			(net "PEX_USB_HUB_XOUT_R")
		)
	)
	(footprint ""
		(layer "F.Cu")
		(at 310.467756 -55.083456)
		(property "Reference" "PC361"
			(at 0 0 0)
			(layer "F.SilkS")
			(hide yes)
			(effects
				(font
					(size 1.27 1.27)
				)
			)
		)
		(property "Value" ""
			(at 0 0 0)
			(layer "F.Fab")
			(effects
				(font
					(size 1.27 1.27)
				)
			)
		)
		(duplicate_pad_numbers_are_jumpers no)
		(fp_line
			(start -0.7874 -0.4064)
			(end 0.7874 -0.4064)
			(stroke
				(width 0.1524)
				(type default)
			)
			(layer "F.SilkS")
		)
		(fp_line
			(start -0.7874 0.4064)
			(end -0.7874 -0.4064)
			(stroke
				(width 0.1524)
				(type default)
			)
			(layer "F.SilkS")
		)
		(fp_line
			(start 0.7874 -0.4064)
			(end 0.7874 0.4064)
			(stroke
				(width 0.1524)
				(type default)
			)
			(layer "F.SilkS")
		)
		(fp_line
			(start 0.7874 0.4064)
			(end -0.7874 0.4064)
			(stroke
				(width 0.1524)
				(type default)
			)
			(layer "F.SilkS")
		)
		(fp_line
			(start -0.67945 -0.305054)
			(end -0.12065 -0.305054)
			(stroke
				(width 0.1)
				(type default)
			)
			(layer "F.Fab")
		)
		(fp_line
			(start -0.67945 0.3048)
			(end -0.67945 -0.305054)
			(stroke
				(width 0.1)
				(type default)
			)
			(layer "F.Fab")
		)
		(fp_line
			(start -0.12065 -0.305054)
			(end -0.12065 -0.2794)
			(stroke
				(width 0.1)
				(type default)
			)
			(layer "F.Fab")
		)
		(fp_line
			(start -0.12065 -0.2794)
			(end 0.12065 -0.2794)
			(stroke
				(width 0.1)
				(type default)
			)
			(layer "F.Fab")
		)
		(fp_line
			(start -0.12065 0.2794)
			(end -0.12065 0.3048)
			(stroke
				(width 0.1)
				(type default)
			)
			(layer "F.Fab")
		)
		(fp_line
			(start -0.12065 0.3048)
			(end -0.67945 0.3048)
			(stroke
				(width 0.1)
				(type default)
			)
			(layer "F.Fab")
		)
		(fp_line
			(start 0.120396 0.2794)
			(end -0.12065 0.2794)
			(stroke
				(width 0.1)
				(type default)
			)
			(layer "F.Fab")
		)
		(fp_line
			(start 0.120396 0.3048)
			(end 0.120396 0.2794)
			(stroke
				(width 0.1)
				(type default)
			)
			(layer "F.Fab")
		)
		(fp_line
			(start 0.12065 -0.3048)
			(end 0.67945 -0.3048)
			(stroke
				(width 0.1)
				(type default)
			)
			(layer "F.Fab")
		)
		(fp_line
			(start 0.12065 -0.2794)
			(end 0.12065 -0.3048)
			(stroke
				(width 0.1)
				(type default)
			)
			(layer "F.Fab")
		)
		(fp_line
			(start 0.67945 -0.3048)
			(end 0.67945 0.3048)
			(stroke
				(width 0.1)
				(type default)
			)
			(layer "F.Fab")
		)
		(fp_line
			(start 0.67945 0.3048)
			(end 0.120396 0.3048)
			(stroke
				(width 0.1)
				(type default)
			)
			(layer "F.Fab")
		)
		(pad "1" smd circle
			(at -0.40005 0)
			(size 0 0)
			(layers "F.Cu" "F.Mask" "F.Paste")
			(net "P5V_AUX")
		)
		(pad "2" smd circle
			(at 0.40005 0)
			(size 0 0)
			(layers "F.Cu" "F.Mask" "F.Paste")
			(net "GND")
		)
	)
	(footprint ""
		(layer "F.Cu")
		(at 219.202 -204.216 180)
		(property "Reference" "C2625"
			(at 0 0 180)
			(layer "F.SilkS")
			(hide yes)
			(effects
				(font
					(size 1.27 1.27)
				)
			)
		)
		(property "Value" ""
			(at 0 0 180)
			(layer "F.Fab")
			(effects
				(font
					(size 1.27 1.27)
				)
			)
		)
		(duplicate_pad_numbers_are_jumpers no)
		(fp_line
			(start 0.7874 0.4064)
			(end -0.7874 0.4064)
			(stroke
				(width 0.1524)
				(type default)
			)
			(layer "F.SilkS")
		)
		(fp_line
			(start 0.7874 -0.4064)
			(end 0.7874 0.4064)
			(stroke
				(width 0.1524)
				(type default)
			)
			(layer "F.SilkS")
		)
		(fp_line
			(start -0.7874 0.4064)
			(end -0.7874 -0.4064)
			(stroke
				(width 0.1524)
				(type default)
			)
			(layer "F.SilkS")
		)
		(fp_line
			(start -0.7874 -0.4064)
			(end 0.7874 -0.4064)
			(stroke
				(width 0.1524)
				(type default)
			)
			(layer "F.SilkS")
		)
		(fp_line
			(start 0.67945 0.3048)
			(end 0.120396 0.3048)
			(stroke
				(width 0.1)
				(type default)
			)
			(layer "F.Fab")
		)
		(fp_line
			(start 0.67945 -0.3048)
			(end 0.67945 0.3048)
			(stroke
				(width 0.1)
				(type default)
			)
			(layer "F.Fab")
		)
		(fp_line
			(start 0.12065 -0.2794)
			(end 0.12065 -0.3048)
			(stroke
				(width 0.1)
				(type default)
			)
			(layer "F.Fab")
		)
		(fp_line
			(start 0.12065 -0.3048)
			(end 0.67945 -0.3048)
			(stroke
				(width 0.1)
				(type default)
			)
			(layer "F.Fab")
		)
		(fp_line
			(start 0.120396 0.3048)
			(end 0.120396 0.2794)
			(stroke
				(width 0.1)
				(type default)
			)
			(layer "F.Fab")
		)
		(fp_line
			(start 0.120396 0.2794)
			(end -0.12065 0.2794)
			(stroke
				(width 0.1)
				(type default)
			)
			(layer "F.Fab")
		)
		(fp_line
			(start -0.12065 0.3048)
			(end -0.67945 0.3048)
			(stroke
				(width 0.1)
				(type default)
			)
			(layer "F.Fab")
		)
		(fp_line
			(start -0.12065 0.2794)
			(end -0.12065 0.3048)
			(stroke
				(width 0.1)
				(type default)
			)
			(layer "F.Fab")
		)
		(fp_line
			(start -0.12065 -0.2794)
			(end 0.12065 -0.2794)
			(stroke
				(width 0.1)
				(type default)
			)
			(layer "F.Fab")
		)
		(fp_line
			(start -0.12065 -0.305054)
			(end -0.12065 -0.2794)
			(stroke
				(width 0.1)
				(type default)
			)
			(layer "F.Fab")
		)
		(fp_line
			(start -0.67945 0.3048)
			(end -0.67945 -0.305054)
			(stroke
				(width 0.1)
				(type default)
			)
			(layer "F.Fab")
		)
		(fp_line
			(start -0.67945 -0.305054)
			(end -0.12065 -0.305054)
			(stroke
				(width 0.1)
				(type default)
			)
			(layer "F.Fab")
		)
		(pad "1" smd circle
			(at -0.40005 0 180)
			(size 0 0)
			(layers "F.Cu" "F.Mask" "F.Paste")
			(net "GND")
		)
		(pad "2" smd circle
			(at 0.40005 0 180)
			(size 0 0)
			(layers "F.Cu" "F.Mask" "F.Paste")
			(net "P3V3_NIC5")
		)
	)
	(footprint ""
		(layer "F.Cu")
		(at 208.185766 -227.10902 90)
		(property "Reference" "R5474"
			(at 0 0 90)
			(layer "F.SilkS")
			(hide yes)
			(effects
				(font
					(size 1.27 1.27)
				)
			)
		)
		(property "Value" ""
			(at 0 0 90)
			(layer "F.Fab")
			(effects
				(font
					(size 1.27 1.27)
				)
			)
		)
		(duplicate_pad_numbers_are_jumpers no)
		(fp_line
			(start 0.7874 -0.4064)
			(end 0.7874 0.4064)
			(stroke
				(width 0.1524)
				(type default)
			)
			(layer "F.SilkS")
		)
		(fp_line
			(start -0.7874 -0.4064)
			(end 0.7874 -0.4064)
			(stroke
				(width 0.1524)
				(type default)
			)
			(layer "F.SilkS")
		)
		(fp_line
			(start 0.7874 0.4064)
			(end -0.7874 0.4064)
			(stroke
				(width 0.1524)
				(type default)
			)
			(layer "F.SilkS")
		)
		(fp_line
			(start -0.7874 0.4064)
			(end -0.7874 -0.4064)
			(stroke
				(width 0.1524)
				(type default)
			)
			(layer "F.SilkS")
		)
		(fp_line
			(start -0.12065 -0.305054)
			(end -0.12065 -0.2794)
			(stroke
				(width 0.1)
				(type default)
			)
			(layer "F.Fab")
		)
		(fp_line
			(start -0.67945 -0.305054)
			(end -0.12065 -0.305054)
			(stroke
				(width 0.1)
				(type default)
			)
			(layer "F.Fab")
		)
		(fp_line
			(start 0.67945 -0.3048)
			(end 0.67945 0.3048)
			(stroke
				(width 0.1)
				(type default)
			)
			(layer "F.Fab")
		)
		(fp_line
			(start 0.12065 -0.3048)
			(end 0.67945 -0.3048)
			(stroke
				(width 0.1)
				(type default)
			)
			(layer "F.Fab")
		)
		(fp_line
			(start 0.12065 -0.2794)
			(end 0.12065 -0.3048)
			(stroke
				(width 0.1)
				(type default)
			)
			(layer "F.Fab")
		)
		(fp_line
			(start -0.12065 -0.2794)
			(end 0.12065 -0.2794)
			(stroke
				(width 0.1)
				(type default)
			)
			(layer "F.Fab")
		)
		(fp_line
			(start 0.120396 0.2794)
			(end -0.12065 0.2794)
			(stroke
				(width 0.1)
				(type default)
			)
			(layer "F.Fab")
		)
		(fp_line
			(start -0.12065 0.2794)
			(end -0.12065 0.3048)
			(stroke
				(width 0.1)
				(type default)
			)
			(layer "F.Fab")
		)
		(fp_line
			(start 0.67945 0.3048)
			(end 0.120396 0.3048)
			(stroke
				(width 0.1)
				(type default)
			)
			(layer "F.Fab")
		)
		(fp_line
			(start 0.120396 0.3048)
			(end 0.120396 0.2794)
			(stroke
				(width 0.1)
				(type default)
			)
			(layer "F.Fab")
		)
		(fp_line
			(start -0.12065 0.3048)
			(end -0.67945 0.3048)
			(stroke
				(width 0.1)
				(type default)
			)
			(layer "F.Fab")
		)
		(fp_line
			(start -0.67945 0.3048)
			(end -0.67945 -0.305054)
			(stroke
				(width 0.1)
				(type default)
			)
			(layer "F.Fab")
		)
		(pad "1" smd circle
			(at -0.40005 0 90)
			(size 0 0)
			(layers "F.Cu" "F.Mask" "F.Paste")
			(net "BUF_UART_MB_BIC_RX_EN")
		)
		(pad "2" smd circle
			(at 0.40005 0 90)
			(size 0 0)
			(layers "F.Cu" "F.Mask" "F.Paste")
			(net "P3V3_AUX")
		)
	)
)
